(kicad_pcb
	(version 20260206)
	(generator "pcbnew")
	(generator_version "10.0")
	(general
		(thickness 1.6)
		(legacy_teardrops no)
	)
	(paper "A4")
	(title_block
		(title "Wiwynn_Tioga_Pass_MB.brd")
		(comment 1 "Tioga Pass / footprints 1486-1493 of 4770")
	)
	(layers
		(0 "F.Cu" signal "TOP")
		(4 "In1.Cu" signal "L2GND")
		(6 "In2.Cu" signal "L3")
		(8 "In3.Cu" signal "L4GND")
		(10 "In4.Cu" signal "L5")
		(12 "In5.Cu" signal "L6GND")
		(14 "In6.Cu" signal "L7VCC")
		(16 "In7.Cu" signal "L8VCC")
		(18 "In8.Cu" signal "L9GND")
		(20 "In9.Cu" signal "L10")
		(22 "In10.Cu" signal "L11GND")
		(24 "In11.Cu" signal "L12")
		(26 "In12.Cu" signal "L13GND")
		(2 "B.Cu" signal "BOTTOM")
		(9 "F.Adhes" user "F.Adhesive")
		(11 "B.Adhes" user "B.Adhesive")
		(13 "F.Paste" user "Package Geometry/Pastemask Top")
		(15 "B.Paste" user "Package Geometry/Pastemask Bottom")
		(5 "F.SilkS" user "Ref Des/Silkscreen Top")
		(7 "B.SilkS" user "Ref Des/Silkscreen Bottom")
		(1 "F.Mask" user "Board Geometry/Soldermask Top")
		(3 "B.Mask" user "Board Geometry/Soldermask Bottom")
		(17 "Dwgs.User" user "User.Drawings")
		(19 "Cmts.User" user "User.Comments")
		(21 "Eco1.User" user "User.Eco1")
		(23 "Eco2.User" user "User.Eco2")
		(25 "Edge.Cuts" user "Board Geometry/Outline")
		(27 "Margin" user)
		(31 "F.CrtYd" user "Package Geometry/Place Bound Top")
		(29 "B.CrtYd" user "Package Geometry/Place Bound Bottom")
		(35 "F.Fab" user "Ref Des/Assembly Top")
		(33 "B.Fab" user "Ref Des/Assembly Bottom")
	)
	(footprint ""
		(layer "F.Cu")
		(at 421.386 -113.8555 180)
		(property "Reference" "R9W13"
			(at -0.8382 -0.67818 180)
			(unlocked yes)
			(layer "F.SilkS")
			(effects
				(font
					(size 0.4064 0.254)
					(thickness 0.1524)
				)
				(justify left)
			)
		)
		(property "Value" ""
			(at 0 0 180)
			(layer "F.Fab")
			(effects
				(font
					(size 1.27 1.27)
				)
			)
		)
		(duplicate_pad_numbers_are_jumpers no)
		(fp_poly
			(pts
				(xy -0.2794 -0.1016) (xy 0.2794 -0.1016) (xy 0.2794 0.9906) (xy -0.2794 0.9906)
			)
			(stroke
				(width 0)
				(type default)
			)
			(fill no)
			(layer "F.CrtYd")
		)
		(fp_line
			(start 0.2794 0.9906)
			(end 0.2794 -0.1016)
			(stroke
				(width 0.1)
				(type default)
			)
			(layer "F.Fab")
		)
		(fp_line
			(start 0.2794 -0.1016)
			(end -0.2794 -0.1016)
			(stroke
				(width 0.1)
				(type default)
			)
			(layer "F.Fab")
		)
		(fp_line
			(start -0.2794 0.9906)
			(end 0.2794 0.9906)
			(stroke
				(width 0.1)
				(type default)
			)
			(layer "F.Fab")
		)
		(fp_line
			(start -0.2794 -0.1016)
			(end -0.2794 0.9906)
			(stroke
				(width 0.1)
				(type default)
			)
			(layer "F.Fab")
		)
		(pad "1" smd rect
			(at 0 0 180)
			(size 0.508 0.508)
			(layers "F.Cu" "F.Mask" "F.Paste")
			(net "SMB_PEHPCPU0_STBY_LVC3_R_SDA")
		)
		(pad "2" smd rect
			(at 0 0.889 180)
			(size 0.508 0.508)
			(layers "F.Cu" "F.Mask" "F.Paste")
			(net "SMB_PEHPCPU0_STBY_LVC3_SDA")
		)
		(zone
			(layer "F.Cu")
			(hatch none 0.5)
			(connect_pads
				(clearance 0)
			)
			(min_thickness 0.25)
			(keepout
				(tracks not_allowed)
				(vias allowed)
				(pads allowed)
				(copperpour not_allowed)
				(footprints allowed)
			)
			(placement
				(enabled no)
				(sheetname "")
			)
			(fill
				(thermal_gap 0.5)
				(thermal_bridge_width 0.5)
				(island_removal_mode 0)
			)
			(polygon
				(pts
					(xy 421.64 -114.4905) (xy 421.132 -114.4905) (xy 421.132 -114.1095) (xy 421.64 -114.1095)
				)
			)
		)
		(zone
			(layer "F.Cu")
			(hatch none 0.5)
			(connect_pads
				(clearance 0)
			)
			(min_thickness 0.25)
			(keepout
				(tracks allowed)
				(vias not_allowed)
				(pads allowed)
				(copperpour not_allowed)
				(footprints allowed)
			)
			(placement
				(enabled no)
				(sheetname "")
			)
			(fill
				(thermal_gap 0.5)
				(thermal_bridge_width 0.5)
				(island_removal_mode 0)
			)
			(polygon
				(pts
					(xy 421.64 -114.1095) (xy 421.132 -114.1095) (xy 421.132 -114.4905) (xy 421.64 -114.4905)
				)
			)
		)
	)
	(footprint ""
		(layer "F.Cu")
		(at 491.426246 -152.15616 -90)
		(property "Reference" "R9A7"
			(at 0 0 270)
			(layer "F.SilkS")
			(hide yes)
			(effects
				(font
					(size 1.27 1.27)
				)
			)
		)
		(property "Value" ""
			(at 0 0 270)
			(layer "F.Fab")
			(effects
				(font
					(size 1.27 1.27)
				)
			)
		)
		(duplicate_pad_numbers_are_jumpers no)
		(fp_poly
			(pts
				(xy -0.2794 -0.1016) (xy 0.2794 -0.1016) (xy 0.2794 0.9906) (xy -0.2794 0.9906)
			)
			(stroke
				(width 0)
				(type default)
			)
			(fill no)
			(layer "F.CrtYd")
		)
		(fp_line
			(start -0.2794 0.9906)
			(end 0.2794 0.9906)
			(stroke
				(width 0.1)
				(type default)
			)
			(layer "F.Fab")
		)
		(fp_line
			(start 0.2794 0.9906)
			(end 0.2794 -0.1016)
			(stroke
				(width 0.1)
				(type default)
			)
			(layer "F.Fab")
		)
		(fp_line
			(start -0.2794 -0.1016)
			(end -0.2794 0.9906)
			(stroke
				(width 0.1)
				(type default)
			)
			(layer "F.Fab")
		)
		(fp_line
			(start 0.2794 -0.1016)
			(end -0.2794 -0.1016)
			(stroke
				(width 0.1)
				(type default)
			)
			(layer "F.Fab")
		)
		(pad "1" smd rect
			(at 0 0 270)
			(size 0.508 0.508)
			(layers "F.Cu" "F.Mask" "F.Paste")
			(net "P3V3_STBY")
		)
		(pad "2" smd rect
			(at 0 0.889 270)
			(size 0.508 0.508)
			(layers "F.Cu" "F.Mask" "F.Paste")
			(net "SPA_SIN_SW_R")
		)
		(zone
			(layer "F.Cu")
			(hatch none 0.5)
			(connect_pads
				(clearance 0)
			)
			(min_thickness 0.25)
			(keepout
				(tracks not_allowed)
				(vias allowed)
				(pads allowed)
				(copperpour not_allowed)
				(footprints allowed)
			)
			(placement
				(enabled no)
				(sheetname "")
			)
			(fill
				(thermal_gap 0.5)
				(thermal_bridge_width 0.5)
				(island_removal_mode 0)
			)
			(polygon
				(pts
					(xy 490.791246 -152.41016) (xy 490.791246 -151.90216) (xy 491.172246 -151.90216) (xy 491.172246 -152.41016)
				)
			)
		)
		(zone
			(layer "F.Cu")
			(hatch none 0.5)
			(connect_pads
				(clearance 0)
			)
			(min_thickness 0.25)
			(keepout
				(tracks allowed)
				(vias not_allowed)
				(pads allowed)
				(copperpour not_allowed)
				(footprints allowed)
			)
			(placement
				(enabled no)
				(sheetname "")
			)
			(fill
				(thermal_gap 0.5)
				(thermal_bridge_width 0.5)
				(island_removal_mode 0)
			)
			(polygon
				(pts
					(xy 491.172246 -152.41016) (xy 491.172246 -151.90216) (xy 490.791246 -151.90216) (xy 490.791246 -152.41016)
				)
			)
		)
	)
	(footprint ""
		(layer "F.Cu")
		(at 101.928168 -79.6036 180)
		(property "Reference" "C2D16"
			(at 0 0 180)
			(layer "F.SilkS")
			(hide yes)
			(effects
				(font
					(size 1.27 1.27)
				)
			)
		)
		(property "Value" ""
			(at 0 0 180)
			(layer "F.Fab")
			(effects
				(font
					(size 1.27 1.27)
				)
			)
		)
		(duplicate_pad_numbers_are_jumpers no)
		(fp_poly
			(pts
				(xy -0.4953 -0.2032) (xy 0.4953 -0.2032) (xy 0.4953 1.6002) (xy -0.4953 1.6002)
			)
			(stroke
				(width 0)
				(type default)
			)
			(fill no)
			(layer "F.CrtYd")
		)
		(fp_line
			(start 0.4953 1.6002)
			(end -0.4953 1.6002)
			(stroke
				(width 0.1)
				(type default)
			)
			(layer "F.Fab")
		)
		(fp_line
			(start 0.4953 -0.2032)
			(end 0.4953 1.6002)
			(stroke
				(width 0.1)
				(type default)
			)
			(layer "F.Fab")
		)
		(fp_line
			(start -0.4953 1.6002)
			(end -0.4953 -0.2032)
			(stroke
				(width 0.1)
				(type default)
			)
			(layer "F.Fab")
		)
		(fp_line
			(start -0.4953 -0.2032)
			(end 0.4953 -0.2032)
			(stroke
				(width 0.1)
				(type default)
			)
			(layer "F.Fab")
		)
		(pad "1" smd rect
			(at 0 0 180)
			(size 0.762 0.889)
			(layers "F.Cu" "F.Mask" "F.Paste")
			(net "PVCCIN_CPU1")
		)
		(pad "2" smd rect
			(at 0 1.397 180)
			(size 0.762 0.889)
			(layers "F.Cu" "F.Mask" "F.Paste")
			(net "GND")
		)
		(zone
			(layer "F.Cu")
			(hatch none 0.5)
			(connect_pads
				(clearance 0)
			)
			(min_thickness 0.25)
			(keepout
				(tracks not_allowed)
				(vias allowed)
				(pads allowed)
				(copperpour not_allowed)
				(footprints allowed)
			)
			(placement
				(enabled no)
				(sheetname "")
			)
			(fill
				(thermal_gap 0.5)
				(thermal_bridge_width 0.5)
				(island_removal_mode 0)
			)
			(polygon
				(pts
					(xy 102.309168 -80.0481) (xy 101.547168 -80.0481) (xy 101.547168 -80.5561) (xy 102.309168 -80.5561)
				)
			)
		)
	)
	(footprint ""
		(layer "F.Cu")
		(at 180.3781 2.4003 180)
		(property "Reference" "R4G23"
			(at 0 0 180)
			(layer "F.SilkS")
			(hide yes)
			(effects
				(font
					(size 1.27 1.27)
				)
			)
		)
		(property "Value" ""
			(at 0 0 180)
			(layer "F.Fab")
			(effects
				(font
					(size 1.27 1.27)
				)
			)
		)
		(duplicate_pad_numbers_are_jumpers no)
		(fp_poly
			(pts
				(xy -0.2794 -0.1016) (xy 0.2794 -0.1016) (xy 0.2794 0.9906) (xy -0.2794 0.9906)
			)
			(stroke
				(width 0)
				(type default)
			)
			(fill no)
			(layer "F.CrtYd")
		)
		(fp_line
			(start 0.2794 0.9906)
			(end 0.2794 -0.1016)
			(stroke
				(width 0.1)
				(type default)
			)
			(layer "F.Fab")
		)
		(fp_line
			(start 0.2794 -0.1016)
			(end -0.2794 -0.1016)
			(stroke
				(width 0.1)
				(type default)
			)
			(layer "F.Fab")
		)
		(fp_line
			(start -0.2794 0.9906)
			(end 0.2794 0.9906)
			(stroke
				(width 0.1)
				(type default)
			)
			(layer "F.Fab")
		)
		(fp_line
			(start -0.2794 -0.1016)
			(end -0.2794 0.9906)
			(stroke
				(width 0.1)
				(type default)
			)
			(layer "F.Fab")
		)
		(pad "1" smd rect
			(at 0 0 180)
			(size 0.508 0.508)
			(layers "F.Cu" "F.Mask" "F.Paste")
			(net "PWRGD_PVDDQ_ABC_R")
		)
		(pad "2" smd rect
			(at 0 0.889 180)
			(size 0.508 0.508)
			(layers "F.Cu" "F.Mask" "F.Paste")
			(net "FM_PVTT_ABC_EN_R")
		)
		(zone
			(layer "F.Cu")
			(hatch none 0.5)
			(connect_pads
				(clearance 0)
			)
			(min_thickness 0.25)
			(keepout
				(tracks not_allowed)
				(vias allowed)
				(pads allowed)
				(copperpour not_allowed)
				(footprints allowed)
			)
			(placement
				(enabled no)
				(sheetname "")
			)
			(fill
				(thermal_gap 0.5)
				(thermal_bridge_width 0.5)
				(island_removal_mode 0)
			)
			(polygon
				(pts
					(xy 180.6321 1.7653) (xy 180.1241 1.7653) (xy 180.1241 2.1463) (xy 180.6321 2.1463)
				)
			)
		)
		(zone
			(layer "F.Cu")
			(hatch none 0.5)
			(connect_pads
				(clearance 0)
			)
			(min_thickness 0.25)
			(keepout
				(tracks allowed)
				(vias not_allowed)
				(pads allowed)
				(copperpour not_allowed)
				(footprints allowed)
			)
			(placement
				(enabled no)
				(sheetname "")
			)
			(fill
				(thermal_gap 0.5)
				(thermal_bridge_width 0.5)
				(island_removal_mode 0)
			)
			(polygon
				(pts
					(xy 180.6321 2.1463) (xy 180.1241 2.1463) (xy 180.1241 1.7653) (xy 180.6321 1.7653)
				)
			)
		)
	)
	(footprint ""
		(layer "F.Cu")
		(at 195.5292 -149.6568 90)
		(property "Reference" "C4A5"
			(at 0 0 90)
			(layer "F.SilkS")
			(hide yes)
			(effects
				(font
					(size 1.27 1.27)
				)
			)
		)
		(property "Value" ""
			(at 0 0 90)
			(layer "F.Fab")
			(effects
				(font
					(size 1.27 1.27)
				)
			)
		)
		(duplicate_pad_numbers_are_jumpers no)
		(fp_poly
			(pts
				(xy 0.3048 -0.1016) (xy 0.3048 0.9906) (xy -0.3048 0.9906) (xy -0.3048 -0.1016)
			)
			(stroke
				(width 0)
				(type default)
			)
			(fill no)
			(layer "F.CrtYd")
		)
		(fp_line
			(start 0.3048 -0.1016)
			(end -0.3048 -0.1016)
			(stroke
				(width 0.1)
				(type default)
			)
			(layer "F.Fab")
		)
		(fp_line
			(start -0.3048 -0.1016)
			(end -0.3048 0.9906)
			(stroke
				(width 0.1)
				(type default)
			)
			(layer "F.Fab")
		)
		(fp_line
			(start 0.3048 0.9906)
			(end 0.3048 -0.1016)
			(stroke
				(width 0.1)
				(type default)
			)
			(layer "F.Fab")
		)
		(fp_line
			(start -0.3048 0.9906)
			(end 0.3048 0.9906)
			(stroke
				(width 0.1)
				(type default)
			)
			(layer "F.Fab")
		)
		(pad "1" smd rect
			(at 0 0 90)
			(size 0.508 0.508)
			(layers "F.Cu" "F.Mask" "F.Paste")
			(net "M_F_VREF")
		)
		(pad "2" smd rect
			(at 0 0.889 90)
			(size 0.508 0.508)
			(layers "F.Cu" "F.Mask" "F.Paste")
			(net "GND")
		)
		(zone
			(layer "F.Cu")
			(hatch none 0.5)
			(connect_pads
				(clearance 0)
			)
			(min_thickness 0.25)
			(keepout
				(tracks allowed)
				(vias not_allowed)
				(pads allowed)
				(copperpour not_allowed)
				(footprints allowed)
			)
			(placement
				(enabled no)
				(sheetname "")
			)
			(fill
				(thermal_gap 0.5)
				(thermal_bridge_width 0.5)
				(island_removal_mode 0)
			)
			(polygon
				(pts
					(xy 195.7832 -149.4028) (xy 195.7832 -149.9108) (xy 196.1642 -149.9108) (xy 196.1642 -149.4028)
				)
			)
		)
		(zone
			(layer "F.Cu")
			(hatch none 0.5)
			(connect_pads
				(clearance 0)
			)
			(min_thickness 0.25)
			(keepout
				(tracks not_allowed)
				(vias allowed)
				(pads allowed)
				(copperpour not_allowed)
				(footprints allowed)
			)
			(placement
				(enabled no)
				(sheetname "")
			)
			(fill
				(thermal_gap 0.5)
				(thermal_bridge_width 0.5)
				(island_removal_mode 0)
			)
			(polygon
				(pts
					(xy 196.1642 -149.4028) (xy 196.1642 -149.9108) (xy 195.7832 -149.9108) (xy 195.7832 -149.4028)
				)
			)
		)
	)
	(footprint ""
		(layer "F.Cu")
		(at 183.388 -4.2545 180)
		(property "Reference" "C4G15"
			(at 0 0 180)
			(layer "F.SilkS")
			(hide yes)
			(effects
				(font
					(size 1.27 1.27)
				)
			)
		)
		(property "Value" ""
			(at 0 0 180)
			(layer "F.Fab")
			(effects
				(font
					(size 1.27 1.27)
				)
			)
		)
		(duplicate_pad_numbers_are_jumpers no)
		(fp_rect
			(start 0.3048 -0.1016)
			(end -0.3048 0.9906)
			(stroke
				(width 0)
				(type default)
			)
			(fill no)
			(layer "F.CrtYd")
		)
		(fp_line
			(start 0.3048 0.9906)
			(end 0.3048 -0.1016)
			(stroke
				(width 0.1)
				(type default)
			)
			(layer "F.Fab")
		)
		(fp_line
			(start 0.3048 -0.1016)
			(end -0.3048 -0.1016)
			(stroke
				(width 0.1)
				(type default)
			)
			(layer "F.Fab")
		)
		(fp_line
			(start -0.3048 0.9906)
			(end 0.3048 0.9906)
			(stroke
				(width 0.1)
				(type default)
			)
			(layer "F.Fab")
		)
		(fp_line
			(start -0.3048 -0.1016)
			(end -0.3048 0.9906)
			(stroke
				(width 0.1)
				(type default)
			)
			(layer "F.Fab")
		)
		(pad "1" smd rect
			(at 0 0 180)
			(size 0.508 0.508)
			(layers "F.Cu" "F.Mask" "F.Paste")
			(net "VR_PVTT_ABC_BIAS")
		)
		(pad "2" smd rect
			(at 0 0.889 180)
			(size 0.508 0.508)
			(layers "F.Cu" "F.Mask" "F.Paste")
			(net "GND")
		)
		(zone
			(layer "F.Cu")
			(hatch none 0.5)
			(connect_pads
				(clearance 0)
			)
			(min_thickness 0.25)
			(keepout
				(tracks not_allowed)
				(vias allowed)
				(pads allowed)
				(copperpour not_allowed)
				(footprints allowed)
			)
			(placement
				(enabled no)
				(sheetname "")
			)
			(fill
				(thermal_gap 0.5)
				(thermal_bridge_width 0.5)
				(island_removal_mode 0)
			)
			(polygon
				(pts
					(xy 183.134 -4.5085) (xy 183.642 -4.5085) (xy 183.642 -4.8895) (xy 183.134 -4.8895)
				)
			)
		)
		(zone
			(layer "F.Cu")
			(hatch none 0.5)
			(connect_pads
				(clearance 0)
			)
			(min_thickness 0.25)
			(keepout
				(tracks allowed)
				(vias not_allowed)
				(pads allowed)
				(copperpour not_allowed)
				(footprints allowed)
			)
			(placement
				(enabled no)
				(sheetname "")
			)
			(fill
				(thermal_gap 0.5)
				(thermal_bridge_width 0.5)
				(island_removal_mode 0)
			)
			(polygon
				(pts
					(xy 183.134 -4.5085) (xy 183.642 -4.5085) (xy 183.642 -4.8895) (xy 183.134 -4.8895)
				)
			)
		)
	)
	(footprint ""
		(layer "F.Cu")
		(at 439.3438 -128.778 180)
		(property "Reference" "C8B6"
			(at 0 0 180)
			(layer "F.SilkS")
			(hide yes)
			(effects
				(font
					(size 1.27 1.27)
				)
			)
		)
		(property "Value" ""
			(at 0 0 180)
			(layer "F.Fab")
			(effects
				(font
					(size 1.27 1.27)
				)
			)
		)
		(duplicate_pad_numbers_are_jumpers no)
		(fp_poly
			(pts
				(xy -0.7239 -0.2159) (xy 0.7239 -0.2159) (xy 0.7239 1.9939) (xy -0.7239 1.9939)
			)
			(stroke
				(width 0)
				(type default)
			)
			(fill no)
			(layer "F.CrtYd")
		)
		(fp_line
			(start 0.7239 1.9939)
			(end 0.7239 -0.2159)
			(stroke
				(width 0.1)
				(type default)
			)
			(layer "F.Fab")
		)
		(fp_line
			(start 0.7239 -0.2159)
			(end -0.7239 -0.2159)
			(stroke
				(width 0.1)
				(type default)
			)
			(layer "F.Fab")
		)
		(fp_line
			(start -0.7239 1.9939)
			(end 0.7239 1.9939)
			(stroke
				(width 0.1)
				(type default)
			)
			(layer "F.Fab")
		)
		(fp_line
			(start -0.7239 -0.2159)
			(end -0.7239 1.9939)
			(stroke
				(width 0.1)
				(type default)
			)
			(layer "F.Fab")
		)
		(pad "1" smd rect
			(at 0 0 180)
			(size 1.27 1.016)
			(layers "F.Cu" "F.Mask" "F.Paste")
			(net "P5V")
		)
		(pad "2" smd rect
			(at 0 1.778 180)
			(size 1.27 1.016)
			(layers "F.Cu" "F.Mask" "F.Paste")
			(net "GND")
		)
		(zone
			(layer "F.Cu")
			(hatch none 0.5)
			(connect_pads
				(clearance 0)
			)
			(min_thickness 0.25)
			(keepout
				(tracks not_allowed)
				(vias allowed)
				(pads allowed)
				(copperpour not_allowed)
				(footprints allowed)
			)
			(placement
				(enabled no)
				(sheetname "")
			)
			(fill
				(thermal_gap 0.5)
				(thermal_bridge_width 0.5)
				(island_removal_mode 0)
			)
			(polygon
				(pts
					(xy 439.9788 -129.286) (xy 438.7088 -129.286) (xy 438.7088 -130.048) (xy 439.9788 -130.048)
				)
			)
		)
	)
	(footprint ""
		(layer "F.Cu")
		(at 485.89184 -123.79706 90)
		(property "Reference" "R9B4"
			(at 0 0 90)
			(layer "F.SilkS")
			(hide yes)
			(effects
				(font
					(size 1.27 1.27)
				)
			)
		)
		(property "Value" ""
			(at 0 0 90)
			(layer "F.Fab")
			(effects
				(font
					(size 1.27 1.27)
				)
			)
		)
		(duplicate_pad_numbers_are_jumpers no)
		(fp_poly
			(pts
				(xy -0.2794 -0.1016) (xy 0.2794 -0.1016) (xy 0.2794 0.9906) (xy -0.2794 0.9906)
			)
			(stroke
				(width 0)
				(type default)
			)
			(fill no)
			(layer "F.CrtYd")
		)
		(fp_line
			(start 0.2794 -0.1016)
			(end -0.2794 -0.1016)
			(stroke
				(width 0.1)
				(type default)
			)
			(layer "F.Fab")
		)
		(fp_line
			(start -0.2794 -0.1016)
			(end -0.2794 0.9906)
			(stroke
				(width 0.1)
				(type default)
			)
			(layer "F.Fab")
		)
		(fp_line
			(start 0.2794 0.9906)
			(end 0.2794 -0.1016)
			(stroke
				(width 0.1)
				(type default)
			)
			(layer "F.Fab")
		)
		(fp_line
			(start -0.2794 0.9906)
			(end 0.2794 0.9906)
			(stroke
				(width 0.1)
				(type default)
			)
			(layer "F.Fab")
		)
		(pad "1" smd rect
			(at 0 0 90)
			(size 0.508 0.508)
			(layers "F.Cu" "F.Mask" "F.Paste")
			(net "ISENSE_TMP421_1_E")
		)
		(pad "2" smd rect
			(at 0 0.889 90)
			(size 0.508 0.508)
			(layers "F.Cu" "F.Mask" "F.Paste")
			(net "ISENSE_TMP421_1_DXP")
		)
		(zone
			(layer "F.Cu")
			(hatch none 0.5)
			(connect_pads
				(clearance 0)
			)
			(min_thickness 0.25)
			(keepout
				(tracks allowed)
				(vias not_allowed)
				(pads allowed)
				(copperpour not_allowed)
				(footprints allowed)
			)
			(placement
				(enabled no)
				(sheetname "")
			)
			(fill
				(thermal_gap 0.5)
				(thermal_bridge_width 0.5)
				(island_removal_mode 0)
			)
			(polygon
				(pts
					(xy 486.14584 -123.54306) (xy 486.14584 -124.05106) (xy 486.52684 -124.05106) (xy 486.52684 -123.54306)
				)
			)
		)
		(zone
			(layer "F.Cu")
			(hatch none 0.5)
			(connect_pads
				(clearance 0)
			)
			(min_thickness 0.25)
			(keepout
				(tracks not_allowed)
				(vias allowed)
				(pads allowed)
				(copperpour not_allowed)
				(footprints allowed)
			)
			(placement
				(enabled no)
				(sheetname "")
			)
			(fill
				(thermal_gap 0.5)
				(thermal_bridge_width 0.5)
				(island_removal_mode 0)
			)
			(polygon
				(pts
					(xy 486.52684 -123.54306) (xy 486.52684 -124.05106) (xy 486.14584 -124.05106) (xy 486.14584 -123.54306)
				)
			)
		)
	)
)
